# S9S_MB_2U (Grand Teton) — schematic netlist excerpt (pin names and nets, part order shuffled) for the footprints in the layout excerpt that follows; sources: Cadence DE-HDL packaged netlist, KiCad conversion of 03242023_DA0F0TMBIJ0_F0T_Motherboard_J_brd_V01_OCP.brd

X18  TP_TDR_4P_FTS  TP_TDR_4P_DIP EMPTY  pkg TH  page 309
  S1  = TDR_DIFF_100_BOT_DP
  P1  = T1_GND
  P2  = T1_GND
  S2  = TDR_DIFF_100_BOT_DN

PC499_P1_8  Q_CAP  22UF 4V 20% X6S  pkg C0805  page 288 : A = PVCCIN_CPU1 ; B = GND

(kicad_pcb
	(version 20260206)
	(generator "pcbnew")
	(generator_version "10.0")
	(general
		(thickness 1.6)
		(legacy_teardrops no)
	)
	(paper "A4")
	(title_block
		(title "03242023_DA0F0TMBIJ0_F0T_Motherboard_J_brd_V01_OCP.brd")
		(comment 1 "Grand Teton / footprints 6036-6037 of 6105")
	)
	(layers
		(0 "F.Cu" signal "TOP")
		(4 "In1.Cu" signal "GND")
		(6 "In2.Cu" signal "IN1")
		(8 "In3.Cu" signal "GND1")
		(10 "In4.Cu" signal "IN2")
		(12 "In5.Cu" signal "GND2")
		(14 "In6.Cu" signal "IN3")
		(16 "In7.Cu" signal "GND3")
		(18 "In8.Cu" signal "VCC")
		(20 "In9.Cu" signal "VCC1")
		(22 "In10.Cu" signal "GND4")
		(24 "In11.Cu" signal "IN4")
		(26 "In12.Cu" signal "GND5")
		(28 "In13.Cu" signal "IN5")
		(30 "In14.Cu" signal "GND6")
		(32 "In15.Cu" signal "IN6")
		(34 "In16.Cu" signal "GND7")
		(2 "B.Cu" signal "BOTTOM")
		(9 "F.Adhes" user "F.Adhesive")
		(11 "B.Adhes" user "B.Adhesive")
		(13 "F.Paste" user "Package Geometry/Pastemask Top")
		(15 "B.Paste" user "Package Geometry/Pastemask Bottom")
		(5 "F.SilkS" user "Ref Des/Silkscreen Top")
		(7 "B.SilkS" user "Ref Des/Silkscreen Bottom")
		(1 "F.Mask" user "Board Geometry/Soldermask Top")
		(3 "B.Mask" user "Board Geometry/Soldermask Bottom")
		(17 "Dwgs.User" user "User.Drawings")
		(19 "Cmts.User" user "User.Comments")
		(21 "Eco1.User" user "User.Eco1")
		(23 "Eco2.User" user "User.Eco2")
		(25 "Edge.Cuts" user "Board Geometry/Outline")
		(27 "Margin" user)
		(31 "F.CrtYd" user "Package Geometry/Place Bound Top")
		(29 "B.CrtYd" user "Package Geometry/Place Bound Bottom")
		(35 "F.Fab" user "Ref Des/Assembly Top")
		(33 "B.Fab" user "Ref Des/Assembly Bottom")
	)
	(footprint ""
		(layer "B.Cu")
		(at 485.20985 -148.045932 -90)
		(property "Reference" "X18"
			(at 3.762248 3.089656 270)
			(unlocked yes)
			(layer "B.SilkS")
			(effects
				(font
					(size 0.7874 0.5842)
					(thickness 0.1524)
				)
				(justify left mirror)
			)
		)
		(property "Value" ""
			(at 0 0 90)
			(layer "B.Fab")
			(effects
				(font
					(size 1.27 1.27)
				)
				(justify mirror)
			)
		)
		(property "Device Type" "TP_TDR_4P_FTS_MPKT4_H025P0200_I"
			(at -1.30175 1.27 180)
			(unlocked yes)
			(layer "B.Fab")
			(hide yes)
			(effects
				(font
					(size 0.635 0.4064)
					(thickness 0.1524)
				)
				(justify mirror)
			)
		)
		(property "User Part Number" "TP15"
			(at -1.30175 1.27 180)
			(unlocked yes)
			(layer "Cmts.User")
			(hide yes)
			(effects
				(font
					(size 0.635 0.4064)
					(thickness 0.1524)
				)
				(justify mirror)
			)
		)
		(duplicate_pad_numbers_are_jumpers no)
		(fp_line
			(start -2.54 3.81)
			(end -2.54 3.6703)
			(stroke
				(width 0.1524)
				(type default)
			)
			(layer "B.SilkS")
		)
		(fp_line
			(start 0 3.81)
			(end -2.54 3.81)
			(stroke
				(width 0.1524)
				(type default)
			)
			(layer "B.SilkS")
		)
		(fp_line
			(start 0 3.175)
			(end 0 3.81)
			(stroke
				(width 0.1524)
				(type default)
			)
			(layer "B.SilkS")
		)
		(fp_line
			(start -2.54 1.4097)
			(end -2.54 1.1303)
			(stroke
				(width 0.1524)
				(type default)
			)
			(layer "B.SilkS")
		)
		(fp_line
			(start 0 0.635)
			(end 0 1.905)
			(stroke
				(width 0.1524)
				(type default)
			)
			(layer "B.SilkS")
		)
		(fp_line
			(start -2.54 -1.1303)
			(end -2.54 -1.27)
			(stroke
				(width 0.1524)
				(type default)
			)
			(layer "B.SilkS")
		)
		(fp_line
			(start -2.54 -1.27)
			(end 0 -1.27)
			(stroke
				(width 0.1524)
				(type default)
			)
			(layer "B.SilkS")
		)
		(fp_line
			(start 0 -1.27)
			(end 0 -0.635)
			(stroke
				(width 0.1524)
				(type default)
			)
			(layer "B.SilkS")
		)
		(fp_poly
			(pts
				(xy 2.958846 -0.84582) (xy 2.958846 0.67818) (xy 1.434846 -0.08382)
			)
			(stroke
				(width 0)
				(type default)
			)
			(fill yes)
			(layer "B.SilkS")
		)
		(fp_line
			(start -2.54 3.81)
			(end -2.54 -1.27)
			(stroke
				(width 0.1)
				(type default)
			)
			(layer "B.Fab")
		)
		(fp_line
			(start 0 3.81)
			(end -2.54 3.81)
			(stroke
				(width 0.1)
				(type default)
			)
			(layer "B.Fab")
		)
		(fp_line
			(start -2.54 -1.27)
			(end 0 -1.27)
			(stroke
				(width 0.1)
				(type default)
			)
			(layer "B.Fab")
		)
		(fp_line
			(start 0 -1.27)
			(end 0 3.81)
			(stroke
				(width 0.1)
				(type default)
			)
			(layer "B.Fab")
		)
		(fp_poly
			(pts
				(xy 0.761746 0) (xy 2.285746 -0.762) (xy 2.285746 0.762)
			)
			(stroke
				(width 0)
				(type default)
			)
			(fill yes)
			(layer "B.Fab")
		)
		(pad "1" thru_hole circle
			(at 0 0 90)
			(size 1.0033 1.0033)
			(drill 0.249936)
			(layers "*.Cu" "*.Mask")
			(remove_unused_layers no)
			(net "TDR_DIFF_100_BOT_DP")
			(clearance 0.10795)
			(padstack
				(mode front_inner_back)
				(layer "Inner"
					(shape circle)
					(size 0.8001 0.8001)
					(clearance 0.1524)
				)
				(layer "B.Cu"
					(shape circle)
					(size 1.0033 1.0033)
					(thermal_gap 0.10795)
					(clearance 0.10795)
				)
			)
		)
		(pad "2" thru_hole circle
			(at -2.54 0 90)
			(size 1.9939 1.9939)
			(drill 0.249936)
			(layers "*.Cu" "*.Mask")
			(remove_unused_layers no)
			(net "T1_GND")
			(clearance 0.10795)
			(padstack
				(mode front_inner_back)
				(layer "Inner"
					(shape circle)
					(size 0.8001 0.8001)
					(clearance 0.1524)
				)
				(layer "B.Cu"
					(shape circle)
					(size 1.9939 1.9939)
					(thermal_gap 0.10795)
					(clearance 0.10795)
				)
			)
		)
		(pad "3" thru_hole circle
			(at -2.54 2.54 90)
			(size 1.9939 1.9939)
			(drill 0.249936)
			(layers "*.Cu" "*.Mask")
			(remove_unused_layers no)
			(net "T1_GND")
			(clearance 0.10795)
			(padstack
				(mode front_inner_back)
				(layer "Inner"
					(shape circle)
					(size 0.8001 0.8001)
					(clearance 0.1524)
				)
				(layer "B.Cu"
					(shape circle)
					(size 1.9939 1.9939)
					(thermal_gap 0.10795)
					(clearance 0.10795)
				)
			)
		)
		(pad "4" thru_hole circle
			(at 0 2.54 90)
			(size 1.0033 1.0033)
			(drill 0.249936)
			(layers "*.Cu" "*.Mask")
			(remove_unused_layers no)
			(net "TDR_DIFF_100_BOT_DN")
			(clearance 0.10795)
			(padstack
				(mode front_inner_back)
				(layer "Inner"
					(shape circle)
					(size 0.8001 0.8001)
					(clearance 0.1524)
				)
				(layer "B.Cu"
					(shape circle)
					(size 1.0033 1.0033)
					(thermal_gap 0.10795)
					(clearance 0.10795)
				)
			)
		)
	)
	(footprint ""
		(layer "B.Cu")
		(at 138.152378 -333.6163 -90)
		(property "Reference" "PC499_P1_8"
			(at 0 0 90)
			(layer "B.SilkS")
			(hide yes)
			(effects
				(font
					(size 1.27 1.27)
				)
				(justify mirror)
			)
		)
		(property "Value" ""
			(at 0 0 90)
			(layer "B.Fab")
			(effects
				(font
					(size 1.27 1.27)
				)
				(justify mirror)
			)
		)
		(duplicate_pad_numbers_are_jumpers no)
		(fp_line
			(start -1.524 0.762)
			(end 1.524 0.762)
			(stroke
				(width 0.1524)
				(type default)
			)
			(layer "B.SilkS")
		)
		(fp_line
			(start 1.524 0.762)
			(end 1.524 -0.762)
			(stroke
				(width 0.1524)
				(type default)
			)
			(layer "B.SilkS")
		)
		(fp_line
			(start -1.524 -0.762)
			(end -1.524 0.762)
			(stroke
				(width 0.1524)
				(type default)
			)
			(layer "B.SilkS")
		)
		(fp_line
			(start 1.524 -0.762)
			(end -1.524 -0.762)
			(stroke
				(width 0.1524)
				(type default)
			)
			(layer "B.SilkS")
		)
		(fp_line
			(start -1.1049 0.724916)
			(end -1.1049 -0.724916)
			(stroke
				(width 0.1)
				(type default)
			)
			(layer "B.Fab")
		)
		(fp_line
			(start 1.1049 0.724916)
			(end -1.1049 0.724916)
			(stroke
				(width 0.1)
				(type default)
			)
			(layer "B.Fab")
		)
		(fp_line
			(start -1.1049 -0.724916)
			(end 1.1049 -0.724916)
			(stroke
				(width 0.1)
				(type default)
			)
			(layer "B.Fab")
		)
		(fp_line
			(start 1.1049 -0.724916)
			(end 1.1049 0.724916)
			(stroke
				(width 0.1)
				(type default)
			)
			(layer "B.Fab")
		)
		(pad "1" smd rect
			(at 0.889 0 270)
			(size 1.016 1.27)
			(layers "B.Cu" "B.Mask" "B.Paste")
			(net "PVCCIN_CPU1")
		)
		(pad "2" smd rect
			(at -0.889 0 270)
			(size 1.016 1.27)
			(layers "B.Cu" "B.Mask" "B.Paste")
			(net "GND")
		)
	)
)
